# SCM (Grand Teton) — schematic netlist excerpt (pin names and nets, part order shuffled) for the footprints in the layout excerpt that follows; sources: Cadence DE-HDL packaged netlist, KiCad conversion of 12092022_DA0F0TMDCD0_F0T_Management_Board_D_brd_V3_OCP.brd

X18  TP_TDR_4P_FTS  TP_TDR_4P_DIP EMPTY  pkg TH  page 60
  S1  = TDR_DIFF_100_BOT_DP
  P1  = GND_P1
  P2  = GND_P1
  S2  = TDR_DIFF_100_BOT_DN

R108  Q_RES  49.9 1% CHIP  pkg 0402LF  page 22 : A = RST_SRST_PLD_BMC_BUF_N ; B = RST_BMC_SRST_BUF_R_N

(kicad_pcb
	(version 20260206)
	(generator "pcbnew")
	(generator_version "10.0")
	(general
		(thickness 1.6)
		(legacy_teardrops no)
	)
	(paper "A4")
	(title_block
		(title "12092022_DA0F0TMDCD0_F0T_Management_Board_D_brd_V3_OCP.brd")
		(comment 1 "Grand Teton / footprints 167-168 of 1440")
	)
	(layers
		(0 "F.Cu" signal "TOP")
		(4 "In1.Cu" signal "GND")
		(6 "In2.Cu" signal "IN1")
		(8 "In3.Cu" signal "GND1")
		(10 "In4.Cu" signal "IN2")
		(12 "In5.Cu" signal "VCC")
		(14 "In6.Cu" signal "VCC1")
		(16 "In7.Cu" signal "IN3")
		(18 "In8.Cu" signal "GND2")
		(20 "In9.Cu" signal "IN4")
		(22 "In10.Cu" signal "GND3")
		(2 "B.Cu" signal "BOTTOM")
		(9 "F.Adhes" user "F.Adhesive")
		(11 "B.Adhes" user "B.Adhesive")
		(13 "F.Paste" user "Package Geometry/Pastemask Top")
		(15 "B.Paste" user "Package Geometry/Pastemask Bottom")
		(5 "F.SilkS" user "Ref Des/Silkscreen Top")
		(7 "B.SilkS" user "Ref Des/Silkscreen Bottom")
		(1 "F.Mask" user "Board Geometry/Soldermask Top")
		(3 "B.Mask" user "Board Geometry/Soldermask Bottom")
		(17 "Dwgs.User" user "User.Drawings")
		(19 "Cmts.User" user "User.Comments")
		(21 "Eco1.User" user "User.Eco1")
		(23 "Eco2.User" user "User.Eco2")
		(25 "Edge.Cuts" user "Board Geometry/Outline")
		(27 "Margin" user)
		(31 "F.CrtYd" user "Package Geometry/Place Bound Top")
		(29 "B.CrtYd" user "Package Geometry/Place Bound Bottom")
		(35 "F.Fab" user "Ref Des/Assembly Top")
		(33 "B.Fab" user "Ref Des/Assembly Bottom")
	)
	(footprint ""
		(layer "F.Cu")
		(at 9.7536 -80.5434)
		(property "Reference" "R108"
			(at 0 0 0)
			(layer "F.SilkS")
			(hide yes)
			(effects
				(font
					(size 1.27 1.27)
				)
			)
		)
		(property "Value" ""
			(at 0 0 0)
			(layer "F.Fab")
			(effects
				(font
					(size 1.27 1.27)
				)
			)
		)
		(duplicate_pad_numbers_are_jumpers no)
		(fp_line
			(start -0.7874 -0.4064)
			(end 0.7874 -0.4064)
			(stroke
				(width 0.1524)
				(type default)
			)
			(layer "F.SilkS")
		)
		(fp_line
			(start -0.7874 0.4064)
			(end -0.7874 -0.4064)
			(stroke
				(width 0.1524)
				(type default)
			)
			(layer "F.SilkS")
		)
		(fp_line
			(start 0.7874 -0.4064)
			(end 0.7874 0.4064)
			(stroke
				(width 0.1524)
				(type default)
			)
			(layer "F.SilkS")
		)
		(fp_line
			(start 0.7874 0.4064)
			(end -0.7874 0.4064)
			(stroke
				(width 0.1524)
				(type default)
			)
			(layer "F.SilkS")
		)
		(fp_line
			(start -0.67945 -0.305054)
			(end -0.12065 -0.305054)
			(stroke
				(width 0.1)
				(type default)
			)
			(layer "F.Fab")
		)
		(fp_line
			(start -0.67945 0.3048)
			(end -0.67945 -0.305054)
			(stroke
				(width 0.1)
				(type default)
			)
			(layer "F.Fab")
		)
		(fp_line
			(start -0.12065 -0.305054)
			(end -0.12065 -0.2794)
			(stroke
				(width 0.1)
				(type default)
			)
			(layer "F.Fab")
		)
		(fp_line
			(start -0.12065 -0.2794)
			(end 0.12065 -0.2794)
			(stroke
				(width 0.1)
				(type default)
			)
			(layer "F.Fab")
		)
		(fp_line
			(start -0.12065 0.2794)
			(end -0.12065 0.3048)
			(stroke
				(width 0.1)
				(type default)
			)
			(layer "F.Fab")
		)
		(fp_line
			(start -0.12065 0.3048)
			(end -0.67945 0.3048)
			(stroke
				(width 0.1)
				(type default)
			)
			(layer "F.Fab")
		)
		(fp_line
			(start 0.120396 0.2794)
			(end -0.12065 0.2794)
			(stroke
				(width 0.1)
				(type default)
			)
			(layer "F.Fab")
		)
		(fp_line
			(start 0.120396 0.3048)
			(end 0.120396 0.2794)
			(stroke
				(width 0.1)
				(type default)
			)
			(layer "F.Fab")
		)
		(fp_line
			(start 0.12065 -0.3048)
			(end 0.67945 -0.3048)
			(stroke
				(width 0.1)
				(type default)
			)
			(layer "F.Fab")
		)
		(fp_line
			(start 0.12065 -0.2794)
			(end 0.12065 -0.3048)
			(stroke
				(width 0.1)
				(type default)
			)
			(layer "F.Fab")
		)
		(fp_line
			(start 0.67945 -0.3048)
			(end 0.67945 0.3048)
			(stroke
				(width 0.1)
				(type default)
			)
			(layer "F.Fab")
		)
		(fp_line
			(start 0.67945 0.3048)
			(end 0.120396 0.3048)
			(stroke
				(width 0.1)
				(type default)
			)
			(layer "F.Fab")
		)
		(pad "1" smd circle
			(at -0.40005 0)
			(size 0 0)
			(layers "F.Cu" "F.Mask" "F.Paste")
			(net "RST_SRST_PLD_BMC_BUF_N")
		)
		(pad "2" smd circle
			(at 0.40005 0)
			(size 0 0)
			(layers "F.Cu" "F.Mask" "F.Paste")
			(net "RST_BMC_SRST_BUF_R_N")
		)
	)
	(footprint ""
		(layer "F.Cu")
		(at 112.014 90.17 90)
		(property "Reference" "X18"
			(at -2.07137 1.0795 0)
			(unlocked yes)
			(layer "F.SilkS")
			(effects
				(font
					(size 0.7874 0.5842)
					(thickness 0.1524)
				)
				(justify left)
			)
		)
		(property "Value" ""
			(at 0 0 90)
			(layer "F.Fab")
			(effects
				(font
					(size 1.27 1.27)
				)
			)
		)
		(property "Device Type" "TP_TDR_4P_FTS_TH-TP_TDR_4P_DIPA"
			(at 1.30175 1.27 180)
			(unlocked yes)
			(layer "F.Fab")
			(hide yes)
			(effects
				(font
					(size 0.635 0.4064)
					(thickness 0.1524)
				)
			)
		)
		(property "User Part Number" "N_A"
			(at 1.30175 1.27 180)
			(unlocked yes)
			(layer "Cmts.User")
			(hide yes)
			(effects
				(font
					(size 0.635 0.4064)
					(thickness 0.1524)
				)
			)
		)
		(duplicate_pad_numbers_are_jumpers no)
		(fp_line
			(start 2.54 -1.27)
			(end 0 -1.27)
			(stroke
				(width 0.1524)
				(type default)
			)
			(layer "F.SilkS")
		)
		(fp_line
			(start 0 -1.27)
			(end 0 -0.635)
			(stroke
				(width 0.1524)
				(type default)
			)
			(layer "F.SilkS")
		)
		(fp_line
			(start 2.54 -1.1303)
			(end 2.54 -1.27)
			(stroke
				(width 0.1524)
				(type default)
			)
			(layer "F.SilkS")
		)
		(fp_line
			(start 0 0.635)
			(end 0 1.905)
			(stroke
				(width 0.1524)
				(type default)
			)
			(layer "F.SilkS")
		)
		(fp_line
			(start 2.54 1.4097)
			(end 2.54 1.1303)
			(stroke
				(width 0.1524)
				(type default)
			)
			(layer "F.SilkS")
		)
		(fp_line
			(start 0 3.175)
			(end 0 3.81)
			(stroke
				(width 0.1524)
				(type default)
			)
			(layer "F.SilkS")
		)
		(fp_line
			(start 2.54 3.81)
			(end 2.54 3.6703)
			(stroke
				(width 0.1524)
				(type default)
			)
			(layer "F.SilkS")
		)
		(fp_line
			(start 0 3.81)
			(end 2.54 3.81)
			(stroke
				(width 0.1524)
				(type default)
			)
			(layer "F.SilkS")
		)
		(fp_poly
			(pts
				(xy -0.761746 0) (xy -2.285746 -0.762) (xy -2.285746 0.762)
			)
			(stroke
				(width 0)
				(type default)
			)
			(fill yes)
			(layer "F.SilkS")
		)
		(fp_line
			(start 2.54 -1.27)
			(end 0 -1.27)
			(stroke
				(width 0.1)
				(type default)
			)
			(layer "F.Fab")
		)
		(fp_line
			(start 0 -1.27)
			(end 0 3.81)
			(stroke
				(width 0.1)
				(type default)
			)
			(layer "F.Fab")
		)
		(fp_line
			(start 2.54 3.81)
			(end 2.54 -1.27)
			(stroke
				(width 0.1)
				(type default)
			)
			(layer "F.Fab")
		)
		(fp_line
			(start 0 3.81)
			(end 2.54 3.81)
			(stroke
				(width 0.1)
				(type default)
			)
			(layer "F.Fab")
		)
		(fp_poly
			(pts
				(xy -0.761746 0) (xy -2.285746 -0.762) (xy -2.285746 0.762)
			)
			(stroke
				(width 0)
				(type default)
			)
			(fill yes)
			(layer "F.Fab")
		)
		(pad "1" thru_hole circle
			(at 0 0 90)
			(size 1.0033 1.0033)
			(drill 0.249936)
			(layers "*.Cu" "*.Mask")
			(remove_unused_layers no)
			(net "TDR_DIFF_100_BOT_DP")
			(clearance 0.10795)
			(thermal_gap 0.10795)
			(padstack
				(mode front_inner_back)
				(layer "Inner"
					(shape circle)
					(size 0.8001 0.8001)
					(clearance 0.1524)
				)
				(layer "B.Cu"
					(shape circle)
					(size 1.0033 1.0033)
					(clearance 0.10795)
				)
			)
		)
		(pad "2" thru_hole circle
			(at 2.54 0 90)
			(size 1.9939 1.9939)
			(drill 0.249936)
			(layers "*.Cu" "*.Mask")
			(remove_unused_layers no)
			(net "GND_P1")
			(clearance 0.10795)
			(thermal_gap 0.10795)
			(padstack
				(mode front_inner_back)
				(layer "Inner"
					(shape circle)
					(size 0.8001 0.8001)
					(clearance 0.1524)
				)
				(layer "B.Cu"
					(shape circle)
					(size 1.9939 1.9939)
					(clearance 0.10795)
				)
			)
		)
		(pad "3" thru_hole circle
			(at 2.54 2.54 90)
			(size 1.9939 1.9939)
			(drill 0.249936)
			(layers "*.Cu" "*.Mask")
			(remove_unused_layers no)
			(net "GND_P1")
			(clearance 0.10795)
			(thermal_gap 0.10795)
			(padstack
				(mode front_inner_back)
				(layer "Inner"
					(shape circle)
					(size 0.8001 0.8001)
					(clearance 0.1524)
				)
				(layer "B.Cu"
					(shape circle)
					(size 1.9939 1.9939)
					(clearance 0.10795)
				)
			)
		)
		(pad "4" thru_hole circle
			(at 0 2.54 90)
			(size 1.0033 1.0033)
			(drill 0.249936)
			(layers "*.Cu" "*.Mask")
			(remove_unused_layers no)
			(net "TDR_DIFF_100_BOT_DN")
			(clearance 0.10795)
			(thermal_gap 0.10795)
			(padstack
				(mode front_inner_back)
				(layer "Inner"
					(shape circle)
					(size 0.8001 0.8001)
					(clearance 0.1524)
				)
				(layer "B.Cu"
					(shape circle)
					(size 1.0033 1.0033)
					(clearance 0.10795)
				)
			)
		)
	)
)
